# SCM (Grand Teton) — schematic netlist excerpt (pin names and nets, part order shuffled) for the footprints in the layout excerpt that follows; sources: Cadence DE-HDL packaged netlist, KiCad conversion of 12092022_DA0F0TMDCD0_F0T_Management_Board_D_brd_V3_OCP.brd

ME1  ME_DUMMY_SYMBOL  QUANTA_LOGO_7X26 EMPTY  pkg QUANTA_LOGO_7X26  page 59

U48  BAS70057F  BAS70-05-7-F IC  pkg SOT23_123XB  page 50
  B  = P3V_BAT_R
  A  = P3V3_AUX
  C  = P3V3_RTC_AUX

J30  PICOPROBE_BXA  DELTA-L 4.0 EMPTY  pkg TRIANG_LAUNCH_3PXB  page 58
  \1_p\  = 85_10INCH_IN1_DP
  \2_n\  = 85_10INCH_IN1_DN
  \3_g\  = GND_P1

(kicad_pcb
	(version 20260206)
	(generator "pcbnew")
	(generator_version "10.0")
	(general
		(thickness 1.6)
		(legacy_teardrops no)
	)
	(paper "A4")
	(title_block
		(title "12092022_DA0F0TMDCD0_F0T_Management_Board_D_brd_V3_OCP.brd")
		(comment 1 "Grand Teton / footprints 1221-1223 of 1440")
	)
	(layers
		(0 "F.Cu" signal "TOP")
		(4 "In1.Cu" signal "GND")
		(6 "In2.Cu" signal "IN1")
		(8 "In3.Cu" signal "GND1")
		(10 "In4.Cu" signal "IN2")
		(12 "In5.Cu" signal "VCC")
		(14 "In6.Cu" signal "VCC1")
		(16 "In7.Cu" signal "IN3")
		(18 "In8.Cu" signal "GND2")
		(20 "In9.Cu" signal "IN4")
		(22 "In10.Cu" signal "GND3")
		(2 "B.Cu" signal "BOTTOM")
		(9 "F.Adhes" user "F.Adhesive")
		(11 "B.Adhes" user "B.Adhesive")
		(13 "F.Paste" user "Package Geometry/Pastemask Top")
		(15 "B.Paste" user "Package Geometry/Pastemask Bottom")
		(5 "F.SilkS" user "Ref Des/Silkscreen Top")
		(7 "B.SilkS" user "Ref Des/Silkscreen Bottom")
		(1 "F.Mask" user "Board Geometry/Soldermask Top")
		(3 "B.Mask" user "Board Geometry/Soldermask Bottom")
		(17 "Dwgs.User" user "User.Drawings")
		(19 "Cmts.User" user "User.Comments")
		(21 "Eco1.User" user "User.Eco1")
		(23 "Eco2.User" user "User.Eco2")
		(25 "Edge.Cuts" user "Board Geometry/Outline")
		(27 "Margin" user)
		(31 "F.CrtYd" user "Package Geometry/Place Bound Top")
		(29 "B.CrtYd" user "Package Geometry/Place Bound Bottom")
		(35 "F.Fab" user "Ref Des/Assembly Top")
		(33 "B.Fab" user "Ref Des/Assembly Bottom")
	)
	(footprint ""
		(layer "B.Cu")
		(at 101.267768 119.38635 -90)
		(property "Reference" "J30"
			(at 6.08965 -1.448562 270)
			(unlocked yes)
			(layer "B.SilkS")
			(effects
				(font
					(size 0.7874 0.5842)
					(thickness 0.1524)
				)
				(justify left mirror)
			)
		)
		(property "Value" ""
			(at 0 0 90)
			(layer "B.Fab")
			(effects
				(font
					(size 1.27 1.27)
				)
				(justify mirror)
			)
		)
		(duplicate_pad_numbers_are_jumpers no)
		(fp_line
			(start -1.2192 2.1082)
			(end 1.2192 2.1082)
			(stroke
				(width 0.1524)
				(type default)
			)
			(layer "B.SilkS")
		)
		(fp_line
			(start 1.2192 2.1082)
			(end 1.2192 -2.1082)
			(stroke
				(width 0.1524)
				(type default)
			)
			(layer "B.SilkS")
		)
		(fp_line
			(start -1.2192 0.818388)
			(end -1.2192 2.1082)
			(stroke
				(width 0.1524)
				(type default)
			)
			(layer "B.SilkS")
		)
		(fp_line
			(start -1.2192 -2.1082)
			(end -1.2192 -0.821944)
			(stroke
				(width 0.1524)
				(type default)
			)
			(layer "B.SilkS")
		)
		(fp_line
			(start 1.2192 -2.1082)
			(end -1.2192 -2.1082)
			(stroke
				(width 0.1524)
				(type default)
			)
			(layer "B.SilkS")
		)
		(pad "" np_thru_hole circle
			(at -3.4671 -1.27 180)
			(size 1.0414 1.0414)
			(drill 1.0414)
			(layers "*.Cu" "*.Mask")
			(clearance 0.381)
			(thermal_gap 0.381)
		)
		(pad "" np_thru_hole circle
			(at -3.4671 1.27 180)
			(size 1.0414 1.0414)
			(drill 1.0414)
			(layers "*.Cu" "*.Mask")
			(clearance 0.381)
			(thermal_gap 0.381)
		)
		(pad "" np_thru_hole circle
			(at 2.8829 -1.27 180)
			(size 1.0414 1.0414)
			(drill 1.0414)
			(layers "*.Cu" "*.Mask")
			(clearance 0.381)
			(thermal_gap 0.381)
		)
		(pad "" np_thru_hole circle
			(at 2.8829 1.27 180)
			(size 1.0414 1.0414)
			(drill 1.0414)
			(layers "*.Cu" "*.Mask")
			(clearance 0.381)
			(thermal_gap 0.381)
		)
		(pad "1" smd rect
			(at -0.8255 -0.249936 180)
			(size 0.3048 0.508)
			(layers "B.Cu" "B.Mask" "B.Paste")
			(net "85_10INCH_IN1_DP")
		)
		(pad "2" smd rect
			(at -0.8255 0.249936 180)
			(size 0.3048 0.508)
			(layers "B.Cu" "B.Mask" "B.Paste")
			(net "85_10INCH_IN1_DN")
		)
		(pad "3" smd circle
			(at 0 0 90)
			(size 0 0)
			(layers "B.Cu" "B.Mask" "B.Paste")
			(net "GND_P1")
		)
		(zone
			(layers "F.Cu" "B.Cu" "In1.Cu" "In2.Cu" "In3.Cu" "In4.Cu" "In5.Cu" "In6.Cu"
				"In7.Cu" "In8.Cu" "In9.Cu" "In10.Cu"
			)
			(hatch none 0.5)
			(connect_pads
				(clearance 0)
			)
			(min_thickness 0.25)
			(keepout
				(tracks not_allowed)
				(vias allowed)
				(pads allowed)
				(copperpour not_allowed)
				(footprints allowed)
			)
			(placement
				(enabled no)
				(sheetname "")
			)
			(fill
				(thermal_gap 0.5)
				(thermal_bridge_width 0.5)
				(island_removal_mode 0)
			)
			(polygon
				(pts
					(arc
						(start 100.924868 115.91925)
						(mid 99.070668 115.91925)
						(end 100.924868 115.91925)
					)
				)
			)
		)
		(zone
			(layers "F.Cu" "B.Cu" "In1.Cu" "In2.Cu" "In3.Cu" "In4.Cu" "In5.Cu" "In6.Cu"
				"In7.Cu" "In8.Cu" "In9.Cu" "In10.Cu"
			)
			(hatch none 0.5)
			(connect_pads
				(clearance 0)
			)
			(min_thickness 0.25)
			(keepout
				(tracks not_allowed)
				(vias allowed)
				(pads allowed)
				(copperpour not_allowed)
				(footprints allowed)
			)
			(placement
				(enabled no)
				(sheetname "")
			)
			(fill
				(thermal_gap 0.5)
				(thermal_bridge_width 0.5)
				(island_removal_mode 0)
			)
			(polygon
				(pts
					(arc
						(start 100.924868 122.26925)
						(mid 99.070668 122.26925)
						(end 100.924868 122.26925)
					)
				)
			)
		)
		(zone
			(layers "F.Cu" "B.Cu" "In1.Cu" "In2.Cu" "In3.Cu" "In4.Cu" "In5.Cu" "In6.Cu"
				"In7.Cu" "In8.Cu" "In9.Cu" "In10.Cu"
			)
			(hatch none 0.5)
			(connect_pads
				(clearance 0)
			)
			(min_thickness 0.25)
			(keepout
				(tracks not_allowed)
				(vias allowed)
				(pads allowed)
				(copperpour not_allowed)
				(footprints allowed)
			)
			(placement
				(enabled no)
				(sheetname "")
			)
			(fill
				(thermal_gap 0.5)
				(thermal_bridge_width 0.5)
				(island_removal_mode 0)
			)
			(polygon
				(pts
					(arc
						(start 103.464868 115.91925)
						(mid 101.610668 115.91925)
						(end 103.464868 115.91925)
					)
				)
			)
		)
		(zone
			(layers "F.Cu" "B.Cu" "In1.Cu" "In2.Cu" "In3.Cu" "In4.Cu" "In5.Cu" "In6.Cu"
				"In7.Cu" "In8.Cu" "In9.Cu" "In10.Cu"
			)
			(hatch none 0.5)
			(connect_pads
				(clearance 0)
			)
			(min_thickness 0.25)
			(keepout
				(tracks not_allowed)
				(vias allowed)
				(pads allowed)
				(copperpour not_allowed)
				(footprints allowed)
			)
			(placement
				(enabled no)
				(sheetname "")
			)
			(fill
				(thermal_gap 0.5)
				(thermal_bridge_width 0.5)
				(island_removal_mode 0)
			)
			(polygon
				(pts
					(arc
						(start 103.464868 122.26925)
						(mid 101.610668 122.26925)
						(end 103.464868 122.26925)
					)
				)
			)
		)
		(zone
			(layer "B.Cu")
			(hatch none 0.5)
			(connect_pads
				(clearance 0)
			)
			(min_thickness 0.25)
			(keepout
				(tracks not_allowed)
				(vias allowed)
				(pads allowed)
				(copperpour not_allowed)
				(footprints allowed)
			)
			(placement
				(enabled no)
				(sheetname "")
			)
			(fill
				(thermal_gap 0.5)
				(thermal_bridge_width 0.5)
				(island_removal_mode 0)
			)
			(polygon
				(pts
					(xy 101.816408 118.26875) (xy 101.720904 118.26875) (xy 101.720904 118.86565) (xy 101.314504 118.86565)
					(xy 101.314504 118.26875) (xy 101.221032 118.26875) (xy 101.221032 118.86565) (xy 100.814632 118.86565)
					(xy 100.814632 118.26875) (xy 100.719128 118.26875) (xy 100.719128 118.96725) (xy 101.816408 118.96725)
				)
			)
		)
	)
	(footprint ""
		(layer "B.Cu")
		(at 43.9674 -106.299 180)
		(property "Reference" "U48"
			(at 2.31267 -0.762 270)
			(unlocked yes)
			(layer "B.SilkS")
			(effects
				(font
					(size 0.7874 0.5842)
					(thickness 0.1524)
				)
				(justify left mirror)
			)
		)
		(property "Value" ""
			(at 0 0 0)
			(layer "B.Fab")
			(effects
				(font
					(size 1.27 1.27)
				)
				(justify mirror)
			)
		)
		(duplicate_pad_numbers_are_jumpers no)
		(fp_line
			(start 1.584198 1.500124)
			(end -1.584198 1.500124)
			(stroke
				(width 0.1524)
				(type default)
			)
			(layer "B.SilkS")
		)
		(fp_line
			(start 1.584198 -1.500124)
			(end 1.584198 1.500124)
			(stroke
				(width 0.1524)
				(type default)
			)
			(layer "B.SilkS")
		)
		(fp_line
			(start -1.584198 1.500124)
			(end -1.584198 -1.500124)
			(stroke
				(width 0.1524)
				(type default)
			)
			(layer "B.SilkS")
		)
		(fp_line
			(start -1.584198 -1.500124)
			(end 1.584198 -1.500124)
			(stroke
				(width 0.1524)
				(type default)
			)
			(layer "B.SilkS")
		)
		(fp_line
			(start 0.700024 1.500124)
			(end -0.700024 1.500124)
			(stroke
				(width 0.1)
				(type default)
			)
			(layer "B.Fab")
		)
		(fp_line
			(start 0.700024 -1.500124)
			(end 0.700024 1.500124)
			(stroke
				(width 0.1)
				(type default)
			)
			(layer "B.Fab")
		)
		(fp_line
			(start -0.700024 1.500124)
			(end -0.700024 -1.500124)
			(stroke
				(width 0.1)
				(type default)
			)
			(layer "B.Fab")
		)
		(fp_line
			(start -0.700024 -1.500124)
			(end 0.700024 -1.500124)
			(stroke
				(width 0.1)
				(type default)
			)
			(layer "B.Fab")
		)
		(pad "1" smd rect
			(at 0.999998 -0.94996 90)
			(size 0.8128 0.9144)
			(layers "B.Cu" "B.Mask" "B.Paste")
			(net "P3V_BAT_R")
		)
		(pad "2" smd rect
			(at 0.999998 0.94996 90)
			(size 0.8128 0.9144)
			(layers "B.Cu" "B.Mask" "B.Paste")
			(net "P3V3_AUX")
		)
		(pad "3" smd rect
			(at -0.999998 0 90)
			(size 0.8128 0.9144)
			(layers "B.Cu" "B.Mask" "B.Paste")
			(net "P3V3_RTC_AUX")
		)
	)
	(footprint ""
		(layer "B.Cu")
		(at 26.924 -34.925)
		(property "Reference" "ME1"
			(at 0 0 0)
			(layer "B.SilkS")
			(hide yes)
			(effects
				(font
					(size 1.27 1.27)
				)
				(justify mirror)
			)
		)
		(property "Value" ""
			(at 0 0 0)
			(layer "B.Fab")
			(effects
				(font
					(size 1.27 1.27)
				)
				(justify mirror)
			)
		)
		(duplicate_pad_numbers_are_jumpers no)
	)
)
